 Zaius / Barreleye G2 Specification Chassis, Motherboard, Lunchbox Power Supply Revision 0.9.0 Authors: Rob Lippert, Staff Software Engineer, Google Aaron Sullivan, Distinguished Engineer, Rackspace Hosting Inc. Adi Gangidi, Senior System Engineer, Rackspace Hosting Inc. Duen Hsu, Hardware Engineer, Ingrasys   


Open Compute Project • Zaius - Barreleye G2 Specification 
http://opencompute.org 2 
1  License and Notices 1.1  Open Compute License Notice This content contained herein, excluding items listed explicitly otherwise, is licensed under an Open Compute Project Hardware License-Permissive (OCPHL-P) license, version 1.0.  A copy of that license is available here:  http://files.opencompute.org/oc/public.php?service=files&t=4ff92fa7622a58051e1e1bd12db53267&download This content is distributed in the hope that it will be useful, but WITHOUT ANY WARRANTY; without even the implied warranty of MERCHANTABILITY or FITNESS FOR A PARTICULAR PURPOSE. All copyrights and trademarks listed herein are property of their respective organization.   



Open Compute Project • Zaius - Barreleye G2 Specification 
http://opencompute.org 3 
1.2  Referenced Technologies Not Licensed Under OCPHL-P CONTRIBUTORS AND LICENSORS OF THIS SPECIFICATION MAY HAVE MENTIONED CERTAIN TECHNOLOGIES THAT ARE MERELY REFERENCED WITHIN THIS SPECIFICATION AND NOT LICENSED UNDER THE OPEN COMPUTE PROJECT HARDWARE LICENSE (PERMISSIVE). THE FOLLOWING IS A LIST OF MERELY REFERENCED TECHNOLOGY:  ●  IBM POWER9 CPU ●  OpenCAPI ●  AST2500 or AST2520 pin-compatible chips ●  OpenPOWER’s open source system firmware ●  OpenBMC source code ●  TI UCD90160 power sequencer ●  TI TUSB2077A USB1.1 hub ●  Amphenol G16CE41210W3EU connector ●  Lotes AUSBS002-K001C05 connector ●  Marvell 88SE9235 ●  Broadcom BCM5719A PCIe network controller ●  Broadcom BCM54612E PHY ●  Broadcom Cub SAS35x48 ●  Reneasas UPD720201K8 ●  Molex MiniFit Sr connector  ●  NVLink ●  PLX PEX9797 IMPLEMENTATION OF THESE TECHNOLOGIES MAY BE SUBJECT TO THEIR OWN LEGAL TERMS.    



Open Compute Project • Zaius - Barreleye G2 Specification 
http://opencompute.org 4 
1.3  IBM and OpenPOWER Notice Page © Copyright International Business Machines Corporation 2015  IBM, the IBM logo, and ibm.com are trademarks or registered trademarks of International Business Machines Corp., registered in many jurisdictions worldwide. Other product and service names might be trademarks of IBM or other companies.  A current list of IBM trademarks is available on the Web at “Copyright and trademark information” at www.ibm.com/legal/copytrade.shtml.  The OpenPOWER word mark and the OpenPOWER Logo mark, and related marks, are trademarks and service marks licensed by OpenPOWER.  Other company, product, and service names may be trademarks or service marks of others.  All information contained in this document is subject to change without notice. The products described in this document are NOT intended for use in applications such as implantation, life support, or other hazardous uses where malfunction could result in death, bodily injury, or catastrophic property damage. The information contained in this document does not affect or change IBM product specifications or warranties. Nothing in this document shall operate as an express or implied license or indemnity under the intellectual property rights of IBM or third parties. All information contained in this document was obtained in specific environments, and is presented as an illustration. The results obtained in other operating environments may vary.   While the information contained herein is believed to be accurate, such information is preliminary, and should not be relied upon for accuracy or completeness, and no representations or warranties of accuracy or completeness are made.   Note: This document contains information on products in the design, sampling and/or initial production phases of development. This information is subject to change without notice. Verify with your IBM field applications engineer that you have the latest version of this document before finalizing a design.  This document and the files listed in this document as components, if any, are intended for development of technology products compatible with Power Architecture®. You may use this document and any files listed in this document as components, for any purpose (commercial or personal) and make modifications and distribute; however, modifications to this document or any files listed in this document as components may violate Power Architecture and should be carefully considered. Any distribution of this document or the files listed in this document as components, if any, or their derivative works shall include this Notice page including but not limited to the IBM warranty disclaimer and IBM liability limitation, and all copyright notices, intellectual property notices, acknowledgments of 



Open Compute Project • Zaius - Barreleye G2 Specification 
http://opencompute.org 5 
contributions, and confidentiality notices of any party. No other licenses, expressed or implied, by estoppel or otherwise, to any intellectual property rights are granted by this document.  THE INFORMATION CONTAINED IN THIS DOCUMENT IS PROVIDED ON AN “AS IS” BASIS. IBM makes no representations or warranties, either express or implied, including but not limited to, warranties of merchantability, fitness for a particular purpose, or non-infringement, or that any practice or implementation of the IBM documentation will not infringe any third party patents, copyrights, trade secrets, or other rights. In no event will IBM be liable for damages arising directly or indirectly from any use of the information contained in this document.  IBM Systems 294 Route 100, Building SOM4 Somers, NY 10589-3216  The IBM home page can be found at ibm.com®.    



Open Compute Project • Zaius - Barreleye G2 Specification 
http://opencompute.org 6 
2  Recognition & Logos This specification and its associated first implementations in hardware were developed and tested by engineers and software developers at Ingrasys (a Foxconn / Hon Hai Industries subsidiary), Google, Rackspace, and IBM, based in part upon material made available through the OpenPOWER Foundation and community members.           
  


Open Compute Project • Zaius - Barreleye G2 Specification 
http://opencompute.org 7 
3  Revision History  Revision Date Name Description 0.1 08/10/2016 Aaron Sullivan Draft Start 0.2 10/1/2016 Adi Gangidi Added Chapters 6-12 0.3 10/10/2016 Rob Lippert Added info on Zaius sled, shelf 0.4 10/14/2016 Aaron Sullivan Reformat for upload to OCP Wiki 
0.5 11/29/2016 Poly Yeh 
1)  Update P/N of SATA and USB/Serial RJ45 stacked connector  2)  Add PCB information of BPx24, EXP and FPDB 3)  Add Barreleye G2 thermal sensor introduction in page 28 4)  Update Memory VR description in page 34 5)  Update NVLink connector to 37-pin 6)  Update mechanical figures  
0.5.1 12/05/2016 Aaron Sullivan 
1)  Updates to Section 1.2 (Referenced Technologies Not Licenseed…) for readability 2)  Removed references to EVT & DVT from section 7.1.  Added reference to OpenCAPI. 3)  Style changes to heading, table, and figure titles throughout document for consistency and readability 4)  Inserted sections 9.9.1 (Zaius Chassis) and 9.9.2 (Barreleye G2 chassis) BMC sensors. 5)  Updated section 10.1 (Thermal Design Requirements) for Barreleye G2 solutions, to support 300W CPUs in 2OU designs. 6)  Update to section 11.6 (CPU Maximum Power). 7)  Updates to section 12 headings and table titles  8)  Moved section 12.1 (Memory Connector…) to section 7.4.4.  DIMM population rules section number changed to 7.4.5. 9)  Added IBM logo and reference to section 2 (Recognition and Logos) 10)  Changes to pagination and graphics sizes for readability 11)  There is a known issue in the BMC block 



Open Compute Project • Zaius - Barreleye G2 Specification 
http://opencompute.org 8 
diagram, with the size of BMC SPI and BIOS SPI flash.  Both of these are listed as 1GB in size at present, and are actually smaller.  This will be corrected in a subsequent revision. 0.5.2 12/07/2016 Aaron Sullivan 1)  Spec now bundled with 3D step files for Zaius 1.5 OU sled and deployment shelf. 0.5.3 12/19/2016 Aaron Sullivan 1)  Spec now bundled with EE BoM files for Zaius 1.5 OU sled and deployment shelf, Barreleye G2 2OU 5xPCIe chassis. 
0.7.0 05/25/2016 Duen Hsu 
1)  Update vendor of USB/Serial RJ45 stacked connector  2)  Add PCB information of Tri-mode BPx24, Tri-mode EXP 3)  Update Barreleye G2 boards info 4)  Update mechanical figures of system 3D in page 48 to page 57 5)  Update Motherboard Component Placement in page 18 6)  Update DIMM/CPU mapping table in page 20 7)  Update the figure of LEDs in the Front Panel in page 28 8)  Update the figure of fan speed control logic for Barreleye G2in page 31 9)  Update the figure of hard drive cage power for Barreleye G2 in page 37 10)  Update the figure of PCIe slots in page 38 11)  Update the figure of LED/Button in page 42  
0.9.0       06/10/2018 Adi Gangidi 1)  Formatting changes, versioning and references to DVT changed to PVT 2)  Downgraded reference to DIMM Speeds in high level summary       



Open Compute Project • Zaius - Barreleye G2 Specification 
http://opencompute.org 9 
4  Table of Contents  1 License and Notices 2 1.1 Open Compute License Notice 2 1.2 Referenced Technologies Not Licensed Under OCPHL-P 3 1.3 IBM and OpenPOWER Notice Page 4 2 Recognition & Logos 6 3 Revision History 7 4 Table of Contents 9 5 Scope 14 6 System Block Diagram 15 7 Product Features: 16 7.1 Barreleye G2 Server Feature List 16 7.2 Zaius Server Feature List 17 7.3 Motherboard Component Placement 18 7.4 Processor and Memory 19 7.4.1 Processor Feature Set 19 7.4.2 Memory 19 7.4.3 Memory Support 19 7.4.4 DIMM Connector 19 7.4.5 DIMM Population Rule 19 7.5 Storage 20 7.6 Printed Circuit Board Information 21 7.6.1 Motherboard 22-Layer Stack-up 22 8 System Firmware (System BIOS) 24 9 BMC – System Interaction 24 9.1 BMC Hardware Overview 24 9.2 BMC Connection Diagram 26 9.3 Management Network Interface 26 9.3.1 BMC-only Gigabit Ethernet (optional) 27 9.3.2 BCM5719A PCIe Gigabit Ethernet LOM (optional) 27 9.4 Local Serial Console and Serial25 9.5 Graphics and GUI 27 9.6 Remote Power Control and Power Policy 27 



Open Compute Project • Zaius - Barreleye G2 Specification 
http://opencompute.org 10 
9.7 LEDs: Power, HDD Status, System Identification, BMC Heartbeat, Faults 28 9.8 Power, Thermal Monitoring and Power Limiting 29 9.9 Sensors 29 9.9.1 Zaius 29 9.9.2 Barreleye G2 30 9.10 System Event Log (SEL) 30 9.11 Fan Speed Control in BMC 30 9.12 BMC Firmware 31 9.13 BMC Firmware Update Methods 31 9.13.1 Physical Method 31 9.13.2 Update BMC via REST API 31 9.14 BIOS Update from BMC 32 9.15 BMC JTAG Debug Connector 32 10 Thermal Design Requirements 33 10.1 Barreleye G2 Server 33 10.2 Zaius Server 33 11 Motherboard Power system 34 11.1 Input Voltage 34 11.2 Power Input Connector and Hot Swap Controller (HSC) Circuit 34 11.3 Power Sequencing 34 11.4 CPU Voltage Regulator (VR) 34 11.5 Memory VR 35 11.6 CPU Maximum Power 35 11.7 Power Efficiency 35 11.8 Power – Voltage Regulation Requirement Guideline 36 11.9 Barreleye G2 Hard Drive Cage Power 37 12 I/O System 38 12.1 PCIe Slot Connector 38 12.2 NV-Link/OpenCAPI 39 12.3 Network 39 12.3.1 BMC-only Gigabit Ethernet (optional) 40 12.3.2 BCM5719A PCIe Gigabit Ethernet LOM (optional) 40 12.3.3 NC-SI 40 12.4 USB 40 



Open Compute Project • Zaius - Barreleye G2 Specification 
http://opencompute.org 11 
12.5 SATA 41 12.6 Buttons and LEDs: 42 12.6.1 Buttons 42 12.6.2 LEDs 43 12.7 Fan Connector & LEDs 43 12.7.1 Barreleye G2 Fans 43 12.7.2 Zaius Fan Connectors 46 12.8 UART Connector 46 12.8.1 System UART 46 12.8.2 BMC Debug UART 47 13 Mechanical 48 13.1 Barreleye G2 – 2OU Mechanical 48 13.1.1 Barreleye G2 Chassis 48 13.1.2 Barreleye G2 Top View 49 13.1.3 Barreleye G2 Front View 51 13.1.4 Barreleye G2 Rear View 51 13.1.5 Barreleye G2 / Zaius Mother Board 52 13.1.6 Barreleye G2 Power Fan Board 53 13.1.7 Barreleye G2 Expander Board 54 13.1.8 Barreleye G2 OCP MEZZ 55 13.1.9 Barreleye G2 Board Plane x 24 56 13.1.10 Barreleye G2 Hard Drive Tray & Installation 57 13.2 Zaius Sled – 2.6” tall 58 13.2.1 Zaius Sled in 1.5OU Deployment Shelf 58 13.3 Rack and Sled Interaction 59 14 Power Distribution from Bus Bar 60 14.1 Barreleye G2 Chassis 60 14.1.1 Barreleye G2 Fan / Power Board 60 14.2 Zaius Sled Bus Bar Connection 62 14.2.1 Zaius Sled/Shelf Connection Detail Views 63 14.3 Motherboard Power Connector 64 14.4 Power Distribution on Motherboard: 64 15 48V Lunch Box 64 15.1 48V Lunch Box Overview 64 



Open Compute Project • Zaius - Barreleye G2 Specification 
http://opencompute.org 12 
15.2 Objectives 65 15.3 Zaius 48V Lunch Box Interfaces 65 15.3.1 AC Connector 65 15.3.2 AC Input Cable 65 15.3.3 Zaius 48V Lunch Box Power Supply Modules (e.g. Rectifiers) 65 16 Regulatory & Safety Requirements 68 16.1 Safety 68 16.2 EMC 68 16.2.1 Emissions 68 16.2.2 Immunity 68 16.2.3 Country Specific EMC Requirement: 69   



Open Compute Project • Zaius - Barreleye G2 Specification 
http://opencompute.org 13 
5  Scope  This document describes the specifications for: ●  Zaius POWER9 motherboard ●  Barreleye G2 server – 2OU ●  Zaius server – 1.5OU Zaius and Barreleye G2 are OpenPOWER-based Open Compute servers, based upon a common Zaius motherboard specification. These servers have mechanical and electrical packages designed for the 48-volt Open Rack v2. Additional chassis form factors that are based on Zaius motherboard will be added to this document in further revisions.  As of this draft, a 1.25 OU variation of the Barreleye G2 chassis remains to be added. The hardware engineering specification provides technical details for the server board’s functional architecture and feature set as well as some mechanical design details.    



Open Compute Project • Zaius - Barreleye G2 Specification 
http://opencompute.org 14 
6  System Block Diagram The Zaius motherboard can seat 2 IBM POWER9 LaGrange CPUs that support DDR4, PCIe Gen4, and NVLink/OpenCAPI. ●  Each POWER9 LaGrange CPU has 8 DDR4 memory channels with 2 DDR4 DIMM slots per memory channel (16 DIMM slots per CPU, 32 DIMM slots total) ●  The communication between CPUs is via two 30-bit X-bus coherent interconnections at 16Gbps  ●  POWER9 LaGrange includes integrated PCI Gen 4 controllers, with a total of 84 lanes spread between processors. ●  Each CPU supports two x8 lanes of NVLink/OpenCAPI @ 25Gbps   


Open Compute Project • Zaius - Barreleye G2 Specification 
http://opencompute.org 15 
7  Product Features: 7.1  Barreleye G2 Server Feature List Server/Chassis name Barreleye G2 Motherboard Name Zaius Chassis Size 2 OU and 1.25 OU (1.25 OU to be added later) CPU IBM POWER9 LaGrange CPUs x 2, 225W TDP CPU, 3899 pin socket Memory 8 DDR4 channels per processor, up to two DIMMs per channel; total 32 DDR4 RDIMMs (2400 MHz@1DPC, 2133MHz@2DPC), 8/16/32/64GB On-board SATA Controller  Marvell 88SE9235, support for 1 standard SATA port, and 1 M.2 2280 SATA port 
Additional Storage  Tri-mode configuration with 20 x NVMe or 24 x SAS / SATA drive slots (SFF-8639), connected via SAS Expander (Broadcom Cub SAS35x48) and PCIe Switch (PLX PEX9797) Board Network (Optional) Broadcom BCM5719A PCIe x4 LAN-­‐‑on-­‐‑motherboard(LOM) with 1 front GbE RJ45, and NC-SI connection to BMC USB Controller  Renesas UPD720201K8, support for USB 3.0. 1 USB3.0 port to front panel, 1 USB2.0 to BMC virtual device hub, and 1 TI TUSB2077A USB1.1 hub provides 5 USB1.1 to PCIe slots Front I/O  1x USB3.0(from Renesas UPD720201K8), 1x USB2.0(from BMC), 1x serial RJ45(from BMC), 2x GbE RJ45(1 from BMC, 1 from LOM), VGA connector(when AST2500 is used), Power/Reset button, STB Power/All Power LED, SATA HDD LED, Boot Status LED, Attention LED, Fault LEDs, POST Card Management ASPEED AST2500/2520 with console to front serial RJ45, RMII1 port to a mux to select between the NC-­‐‑SI HDMI connector, the MEZZ slot or BCM5719A LOM, and RMII2 port to a Broadcom BCM54612 PHY and front GbE RJ45 PCI-e Slot 1 x16 Gen4 Single-Slot, 2 x8 Gen4 Expanded-Slot, 1 x16 1.5-Slot, 1 x16 Double-Slot, and 1 x16 OCP Mezz 2.0 slot. Board Size MB : 13"Wx22.2"L (Dimensions are not final) SKU SKU1: Support 2 PCIe GPU and 1 x8 PCIe card; SKU2: Support 2 SXM2 GPU and 1 x8 PCIe card; SKU3: Support 5 PCIe cards 
7.2  Zaius Server Feature List Server/Chassis name Zaius 



Open Compute Project • Zaius - Barreleye G2 Specification 
http://opencompute.org 16 
Motherboard Name Zaius Chassis Size 1.5 OU  CPU IBM POWER9 LaGrange CPUs x 2, 225W TDP CPU, 3899 pin socket Memory 8 DDR4 channels per processor, up to two DIMMs per channel; total 32 DDR4 RDIMMs (2400 MHz@1DPC, 2133MHz@2DPC), 8/16/32/64GB On-board SATA Controller  Marvell 88SE9235, support for 1 standard 22-pin SATA port, and 1 M.2 2280 SATA port USB Controller  Renesas UPD720201K8, support for USB 3.0. 1 USB3.0 port to front panel, 1 USB2.0 to BMC virtual device hub, and 1 TI TUSB2077A USB1.1 hub provides 5 USB1.1 to PCIe slots Front I/O  1x USB3.0(from Renesas UPD720201K8), 1x USB2.0(from BMC), 1x serial RJ45(from BMC), 1x GbE RJ45(1 from BMC), Power/Reset button, STB Power/All Power LED, SATA HDD LED, Boot Status LED, Attention LED, Fault LEDs, POST Card Management ASPEED AST2520 with console to front serial RJ45, RMII1 port to a mux to select between the NC-­‐‑SI HDMI connector and MEZZ slot, and RMII2 port to a Broadcom BCM54612 PHY and front GbE RJ45 PCI-e Slot 1 x16 Gen4 Single-Slot, 2 x8 Gen4 Expanded-Slot, 1 x16 1.5-Slot, 1 x16 Double-Slot, and 1 x16 OCP Mezz 2.0 slot. Board Size MB : 13"Wx22.2"L  
   



Open Compute Project • Zaius - Barreleye G2 Specification 
http://opencompute.org 17 
7.3  Motherboard Component Placement Figure: Motherboard Component Placement 
 


Open Compute Project • Zaius - Barreleye G2 Specification 
http://opencompute.org 18 
7.4   Processor and Memory 7.4.1  Processor Feature Set IBM POWER9 LaGrange CPU. 190W, 225W and 300W TDP CPUs available. 3899 pin socket.   7.4.2  Memory  Each LaGrange CPU implements four Memory Bus Adapters (MBAs), each of which can control 2 independent DDR4 channels.  Zaius has two DDR4 DIMM slots per memory channel (16 DIMM slots per CPU, 32 DIMM slots total).  One or two DIMMs may be installed on each channel, following the IBM population rules. 7.4.3  Memory Support The primary form of memory supported on this platform are Single and Dual Rank DDR4 RDIMMs with ECC of sizes 4 GB, 8 GB, 16 GB, 32 GB and 64GB.  Full list of DIMMs supported will added to this document in future revisions. 7.4.4  DIMM Connector DIMM connectors are 288-pin DDR4 compliant and are spaced at 0.34” pitch (i.e. 0.34” between pin 1 of adjacent DIMM slots). DIMM sockets support up to 25 mating cycles and have guard rails at each end. LLCR (low level contact resistance) DIMM sockets are applied. 7.4.5  DIMM Population Rule The Zaius motherboard has two DDR4 DIMM slots per memory channel (16 DIMM slots per CPU, 32 DIMM slots total).  One or two DIMMs may be installed on each channel, following the IBM population rules. The table below illustrates CPU memory channel and DIMM interconnect mappings.  The CPU memory channels A are the “outer” DIMMs (furthest from CPU, blue colored sockets), while memory channels B are the “inner” DIMMs (closest to CPU, black colored sockets).   



Open Compute Project • Zaius - Barreleye G2 Specification 
http://opencompute.org 19 
Table: DIMM/CPU Mapping DIMM CPU Channel DIMM  CPU  Channel  DIMM16 CPU0 DDR6 A DIMM0 CPU0 DDR5 A DIMM17 CPU0 DDR6 B DIMM1 CPU0 DDR5 B DIMM18 CPU0 DDR4 A DIMM2 CPU0 DDR7 A DIMM19 CPU0 DDR4 B DIMM3 CPU0 DDR7 B DIMM20 CPU0 DDR0 B DIMM4 CPU0 DDR1 B DIMM21 CPU0 DDR0 A DIMM5 CPU0 DDR1 A DIMM22 CPU0 DDR2 B DIMM6 CPU0 DDR3 B DIMM23 CPU0 DDR2 A DIMM7 CPU0 DDR3 A DIMM24 CPU1 DDR6 A DIMM8 CPU1 DDR5 A DIMM25 CPU1 DDR6 B DIMM9 CPU1 DDR5 B DIMM26 CPU1 DDR4 A DIMM10 CPU1 DDR7 A DIMM27 CPU1 DDR4 B DIMM11 CPU1 DDR7 B DIMM28 CPU1 DDR0 B DIMM12 CPU1 DDR1 B DIMM29 CPU1 DDR0 A DIMM13 CPU1 DDR1 A DIMM30 CPU1 DDR2 B DIMM14 CPU1 DDR3 B DIMM31 CPU1 DDR2 A DIMM15 CPU1 DDR3 A  For deployment, only full and half-population of DIMM sockets are supported.  When there is half-population of memory, only the outer blue DIMM of each memory channel is installed e.g. only DIMMs 0, 2, 5, 7, 8, 10, 13, 15, 16, 18, 21, 23, 24, 26, 29, 31 are installed.   It’s possible to boot the system when just one DIMM is populated on any memory channel. 7.5  Storage Storage consists of 2 forms: On-board storage and in-chassis storage cage. In chassis-storage cage consisting of a storage back-plane is typically wired to the motherboard via PCIe RAID controller and Expander board   Barreleye G2 2 OU  Zaius Chassis 1.5 OU  On-board Storage 1 M2 SATA and 1 SATA HDD (3.5”/2.5”) 1 M2 SATA and 1 SATA HDD (3.5”/2.5”) 



Open Compute Project • Zaius - Barreleye G2 Specification 
http://opencompute.org 20 
In-Chassis Drive Cage Support 20 NVMe or 24 SATA / SAS Drives N/A 
7.6  Printed Circuit Board Information Each PCB material and stack-up are defined in the table below.  Board PCB Material PCBA Dimension (L*W*H)（mm） Motherboard TU872SLK low-loss material 564x330x3 Tri-mode HDD Back Plane X24 (Barreleye G2 Only) IT-150DA 536.5 x 88.15 x 4.15 Tri-mode Expander Board (Barreleye G2 Only) TU-862HF 232 x 130 x 2.37 Fan / Power Board (Barreleye G2 Only) IT-180I / NP-175F 304.8 x 153.15 x 1.57 RMC board (Barreleye G2 Only) IT-180/ IT-180A 358.3 x 76 x 1.6    



Open Compute Project • Zaius - Barreleye G2 Specification 
http://opencompute.org 21 
7.6.1  Motherboard 22-Layer Stack-up Layer Name Description Material Thickness Copper (Oz) Dielectric (Er)  Solder Mask  0.50    Signal1 SIGNAL Copper 2.00  0.5 + 1 (plating)     PREPREG (2-ply) LL FR4 3.60    3.1 GPlane2 GND Copper 1.20  1.0      CORE LL FR4 4.00    3.3 Signal3 SIGNAL Copper 1.20  1.0      PREPREG LL FR4 4.50    3.3 GPlane4 GND Copper 1.20  1.0      CORE LL FR4 4.00    3.3 Signal5 SIGNAL Copper 1.20  1.0      PREPREG LL FR4 4.50    3.3 GPlane6 GND Copper 1.20  1.0      CORE LL FR4 4.00    3.3 Signal7 SIGNAL Copper 1.20  1.0      PREPREG LL FR4 4.50    3.3 GPlane8 GND Copper 1.20  1.0      CORE LL FR4 4.00    3.3 Signal9 SIGNAL Copper 1.20  1.0      PREPREG LL FR4 4.50    3.3 GPlane10 GND Copper 1.20  1.0      CORE LL FR4 4.00    3.3 PPlane11 PWR Copper 2.50  2.0      PREPREG LL FR4 7.00    3.2 PPlane12 PWR Copper 2.50  2.0      CORE LL FR4 4.00    3.3 GPlane13 GND Copper 1.20  1.0      PREPREG LL FR4 4.50    3.3 Signal14 SIGNAL Copper 1.20  1.0      CORE LL FR4 4.00    3.3 GPlane15 GND Copper 1.20  1.0      PREPREG LL FR4 4.50    3.3 Signal16 SIGNAL Copper 1.20  1.0      CORE LL FR4 4.00    3.3 GPlane17 GND Copper 1.20  1.0      PREPREG LL FR4 4.50    3.3 Signal18 SIGNAL Copper 1.20  1.0      CORE LL FR4 4.00    3.3 



Open Compute Project • Zaius - Barreleye G2 Specification 
http://opencompute.org 22 
GPlane19 GND Copper 1.20  1.0      PREPREG LL FR4 4.50    3.3 Signal20 SIGNAL Copper 1.20  1.0      CORE LL FR4 4.00    3.3 GPlane21 GND Copper 1.20  1.0      PREPREG (2-ply) LL FR4 3.60    3.1 Signal22 SIGNAL Copper 2.00  0.5 + 1 (plating)    Solder Mask  0.50       



Open Compute Project • Zaius - Barreleye G2 Specification 
http://opencompute.org 23 
8  System Firmware (System BIOS)  Zaius uses OpenPOWER’s open source system firmware, made available under open source licensing schemes.  The OpenPOWER firmware stack is available at https://github.com/open-power. Zaius system based machine configuration data files will be added to this repository soon. BIOS update methods are available with documentation on https://github/open-power. 
9  BMC – System Interaction The Zaius motherboard uses a BMC (AST2500 or AST 2520 chips) for various platform management services and interfaces with hardware, BIOS. The BMC is a standalone system in parallel to the host. The health status of the host system should not affect the normal operation and network connectivity of the BMC. The BMC cannot share memory with the host system. BMC management connectivity should work independently from the host. If using a shared NIC, there should be no NIC driver dependency for out-of-band (OOB) communication. 9.1  BMC Hardware Overview Zaius Motherboard is designed to support dual layout of either AST2500 or AST2520 pin-compatible chips.  BoM stuffing options are provided to tie off unused PCIe/VGA pins as specified in AST2520 datasheet when AST2520 is installed. Barreleye G2 Chassis specifically uses AST2500 for its BMC. ASPEED AST2500 or AST2520 device is connected to the CPU0 LPC bus (refer to Section 5 block diagram) and is used to provide the following functions on Zaius motherboard: ●  Fan Monitoring and Control ●  Serial Port ●  Port 80 Decode to LEDs ●  Environmental monitoring ●  Remote serial console and reporting capabilities through NC-SI ●  SMBus Master (thermal sensors, power monitors) ●  FSI master to CPU0 ●  Virtual USB device slave ●  USB host for BMC ●  BIOS SPI master ●  Gigabit Ethernet ●  VGA controller (AST2500 only) The BMC has its own peripherals: ●  1GB (512Mx16) DDR4 memory ●  64MB socketed SOIC16 SPI flash (BMC firmware interface CS0#) ●  8MB soldered-down writable/scratch SPI flash (BMC SPI2) ●  Battery backup (3.3V VBAT for SRAM) ●  I2C RTC (PCF8523)   



Open Compute Project • Zaius - Barreleye G2 Specification 
http://opencompute.org 24 
9.2  BMC Connection Diagram The following diagram provides an overview of the BMC connections on the Zaius motherboard.  These connections may change between the present revision and the final release. Figure: BMC Connection Diagram 
  9.3  Management Network Interface Zaius motherboard front panel optionally provides 2 RJ45 gigabit Ethernet connections in a dual stack connector.  The top Ethernet port connects to BCM5719A PCIe Ethernet. The bottom port connects to BMC-only BCM54612 PHY. 9.3.1  BMC-only Gigabit Ethernet (optional) A Broadcom BCM54612 RGMII capable PHY and front panel RJ45 connector with LINK and ACT LEDs will be used to connect BMC port RGMII2.  This Ethernet port is only usable by the BMC for management purposes and is not connected to any PCIe controllers hosted by Power9 CPUs.   


Open Compute Project • Zaius - Barreleye G2 Specification 
http://opencompute.org 25 
9.3.2  BCM5719A PCIe Gigabit Ethernet LOM (optional) A Broadcom BCM5719A PCIe network controller is used in an optionally stuffed LAN-on-motherboard (LOM) role.  Port 0 of the controller connects to a front panel RJ45 connector with LINK and ACT LEDs, the other ports are unused.  The 4X PCIe lanes for the LOM are connected to lanes 8,9,10,11 of the LOM+VGA connector (optional). NC-SI signals of the BCM5719A are be connected to the BMC as specified in the block diagram. 9.4  Local Serial Console and Serial-­‐‑Over-­‐‑LAN (SOL) The BMC will support two access paths to the serial console: ●  A local serial console on RJ45 serial port ●  A remote console, available via Secure Shell (SSH), through the management network. 9.5  Graphics and GUI Graphic and GUI features integrated in BMC (ASPEED AST2500 series) chip.  Graphics and GUI are optional.  This specification also makes reference to ASPEED AST2520 solutions, without graphics support. 9.6  Remote Power Control and Power Policy BMC firmware will support remote system power on/off/cycle and warm reboot through the REST or SSH commands. BMC firmware will support power on policy to be last-state, always-on and always-off. The default setting is Last-State. The change of power policy should be supported by REST or SSH command and take effect without a BMC firmware cold reset or a system reboot. A reset button (black) and a power button (blue) are mounted at the front edge of the Motherboard. Power Button is on the left of the Reset button. All devices are capable of being manually reset to a known state via the Reset button. The power button is pressed for ~4 seconds to power off the server. When the system is powered off a press and release of the power button would power the server on.  More details on exact timing of power and reset button press and subsequent behavior will be added in the next revisions of this document as it is refined.  9.7  LEDs: Power, HDD Status, System Identification, BMC Heartbeat, Faults These LEDs are located on the front edge of the PCB and exposed to the front panel.  They will be clearly labeled on the silkscreen. On front panel of the tray LEDs are listed in the preferred left-to-right order as seen in the below front panel picture: ●  Blue LED: Indicates standby power good. ●  Green LED: Indicates All Power Good (from Sequencer). ●  Green LED: System Boot Status (driven from BMC GPIO) 



Open Compute Project • Zaius - Barreleye G2 Specification 
http://opencompute.org 26 
●  Yellow LED: Indicates HDD activity.  There is a GPIO0 signal from the Marvell 88SE9235 for SATA drive activity.  ●  Yellow LED: Attention (machine locator, driven from BMC GPIO) - this LED should be placed away from the HDD activity LED, either on the left or right side of the mother board. ●  Red LED: Platform fault.  Driven from BMC GPIO. ●  Red LED: Onboard drive fault.  Driven from BMC GPIO 
 Figure: LEDs in the Front Panel of Barreleye G2 Tray  9.8  Power, Thermal Monitoring and Power Limiting The following hardware monitoring is being provided: ●  Voltage monitoring is performed by the TI UCD90160 sequencer device and BMC. ●  System fan monitoring and control is performed by the BMC. ●  Power monitoring, limiting and thermal monitoring may be performed by the BMC and/or processor OCC. The following points to be monitored for power: ●  48V input to tray (at the hotswap controller) ●  CPU core input at 48V ●  Memory input at 48V ●  System 12V input at 48V ●  Power monitoring connections for off-board drive tray or other I/O device. 9.9  Sensors 9.9.1  Zaius The Zaius motherboard will provide 4 headers for tray-level thermal air temperature sensors.  The thermal sensor will stand approximately 1.6in above the board within the footprint of the connector.  One sensor will be in the front/center (inlet sensor), one will be rear/center, and two will be rear/corners behind each CPU.  The font inlet sensor to be placed vertically, with pin 1 facing the rear of the motherboard.  The rear sensors to be placed horizontally, with pin 1 facing the right of the motherboard. The thermal sensors will be directly connected to the BMC using 1-wire interfaces.  Each sensor should be connected to a separate 1-wire interface for location determination purposes.  The AST25X0 BMC does not have native 1-wire support, 1-wire support will be provided by a GPIO and Linux kernel emulation layer (w1_gpio driver). 


Open Compute Project • Zaius - Barreleye G2 Specification 
http://opencompute.org 27 
 Table: Thermal Header Pinout Pin Signal 1 VDD 2 1-wire data 3 GND  9.9.2  Barreleye G2 The Barreleye G2 system uses three TMP75AIDR thermal chips that is requiring no external components and specified for operation over one temperature range of −40°C to +125°C with a resolution of 0.0625°C. Three thermal sensors will be directly connected to the BMC using two-wire SMBus interface. Two sensors, which are located in front of the motherboard and on fan board, are used to monitor server inlet and outlet temperature. The third temperature sensor on HDD board is to monitor temperature of HDDs.  Table: Thermal Address Sensor Location BMC I2C Port BMC I2C Address Application 
1 Motherboard I2C1 0x4A Server inlet temperature 2 Fan board I2C10 0x72 Server outlet temperature 3 HDD board I2C10 0x4F HDD temperature  9.10  System Event Log (SEL) System event logs to be accessible via BMC using SSH or REST interface. A more conclusive list and description of all events to be logged is still under development and will added in future revisions.  9.11  Fan Speed Control in BMC System fan control and monitoring is provided by BMC on Zaius motherboard. System fan headers support 12V fans. With High-Z PWM output from BMC (e.g. when BMC is first being configured at power-on), system fans should run at full speed.  Resistor pull-up options to be included on the motherboard.  



Open Compute Project • Zaius - Barreleye G2 Specification 
http://opencompute.org 28 
For Barreleye G2 chassis an extra fan control board (using PWM comparator NCT73685) helps set the fans to full speed in cases where BMC crashes / goes down abruptly.  Figure: Fan Speed Control logic in Barreleye G2 
 Fan control behavior to change by chassis and in further revisions. Fan control table will be maintained by revision control for each chassis in OpenBMC repository. Chassis specific fan control details to be added in this spec in further revisions.  9.12  BMC Firmware Machines based on Zaius platform can support a variety of BMC firmware solutions, including OpenBMC.  OpenBMC is available primarily through its GitHub repository: 1.  The OpenBMC / OpenBMC repository: https://github.com/openbmc/openbmc a.  This repository will include most OpenPOWER & Zaius based chassis specific contributions. b.  Specific drivers for OpenPOWER machines were contributed here: https://github.com/openbmc/openbmc/tree/master/meta-openbmc-machines/meta-openpower OpenBMC source code is available under its own license scheme.  9.13  BMC Firmware Update Methods 9.13.1  Physical Method Replace BMC Chip with the updated one. A figure showing the location of replaceable BMC ROM to be added in future revisions. 9.13.2  Update BMC via REST API  Exact procedure to be added in future revisions after validation. 9.14  BIOS Update from BMC  ●  Transfer a copy of the BIOS image (eg. bios.pnor) to flash into the /tmp directory of OpenBMC ●  Use the "pflash" utility to erase and program the BIOS PNOR: 


Open Compute Project • Zaius - Barreleye G2 Specification 
http://opencompute.org 29 
o  pflash -E -p /tmp/bios.pnor The pflash utility might be getting replaced by another BMC utility, during development of this specfication. This document will be updated with corresponding changes in future revisions.  9.15  BMC JTAG Debug Connector With either AST BMC device, the JTAG debug interface shall be available through the "10-pin connector for ARM targets" as defined in ULINK2 Target Connectors. Table: BMC signals available at the JTAG connector Pin Signal Signal Pin 1 VCC_3V3 JTAG_TMS 2 3 GND JTAG_TCK 4 5 GND JTAG_TDO 6 7 JTAG_RTCK JTAG_TDI 8 9 GND SRST# * 10 * SRST# refers to the system reset pin of BMC device, not its JTAG TRST pin.   



Open Compute Project • Zaius - Barreleye G2 Specification 
http://opencompute.org 30 
10  Thermal Design Requirements 10.1  Barreleye G2 Server For Barreleye G2, thermal design should support 35degC ambient under one fan failed condition.  This should be possible with 2 x 225W Power9 in 1.25OU chassis designs / and 2 x 300W Power9 CPUs in 2 OU chassis designs.  Description Requirement System loading Idle to 100% Datacenter operating temperatures 20C to 40C DIMMs Tcase < 75C at all operating conditions CPUs  Per IBM required values Fan Redundancy N+1 redundancy is required  10.2  Zaius Server Zaius server is designed to operate under these thermal conditions:  Description Requirement System loading Idle to 100% Inlet air temperature range <32°C * CPU throttling is not permitted in this range.  * All components must remain below their max spec temperatures Machine ΔT  >11°C Cold-Aisle Pressurization TBD Relative Humidity 8% to 90%, non-condensing Location of Data Center/Altitude  1800 meters above sea level or lower DIMMs Tcase < 75C at all operating conditions CPUs  Per IBM required values System thermal sensors max allowable tolerance ±1°C Fan Redundancy N+1 redundancy is not required 
   



Open Compute Project • Zaius - Barreleye G2 Specification 
http://opencompute.org 31 
11  Motherboard Power system 11.1  Input Voltage The system uses an always-on power supply unit that delivers a fixed unregulated voltage to Zaius motherboard in the range 40V to 60V; VRs are designed to support this input range. 48V will be regulated down to 12V on motherboard. Regulation down to other rails will be from the 12V rail.  48V will also be regulated down to the CPU core voltage and DDR voltage using CPU and Memory VR respectively.  11.2   Power Input Connector and Hot Swap Controller (HSC) Circuit  Zaius motherboard will use an on-board input power connector to receive 48V from the rear of the tray. Directly next to the 48V input connector to the motherboard will be a fuse / hot-swap circuit. The circuit is based on Analog Devices ADM1272 hot swap controller. HOTSWAP_PWR_CYCLE_N signal is driven from BMC and is opto-coupled and sent to the 48V hot swap device enable signal.  It can be used for quasi-AC power cycle for test enabling. Full details on Hot swap controller circuit and how it is leveraged to be added in further revisions of this document.   11.3  Power Sequencing IBM-specified power sequencing requirements are observed for both power up and power down. The TI UCD90160 power sequencer is used for Zaius CPU rail power sequencing.  A signal from BMC is used to reset the sequencer directly.  The sequencer is controlled by the BMC. 11.4  CPU Voltage Regulator (VR) Zaius motherboard provides AVS-compliant VRs to supply the CPU core (VDD/VCS/VDN) rails. More details to be added in further revisions of this document. 11.5  Memory VR Zaius uses AVS-compliant regulator which is directly converted from 48V to power VDDQ power rail. VPP and VTT are converted from 12V and VDDQ respectively by voltage regulators. More details to be added in further revisions of this document. 11.6  CPU Maximum Power The motherboard and VR Module interconnect solution implemented on the motherboard is designed for 225W CPUs (with 3 x 75 watt VRs) as a baseline requirement with a potential of supporting up to 300W (with 4 x 75 watt VRs), in future revisions of this this specification. 



Open Compute Project • Zaius - Barreleye G2 Specification 
http://opencompute.org 32 
11.7  Power Efficiency The target efficiency for VRDs that deliver greater than 10W is 92%; otherwise 75% is the target efficiency.     



Open Compute Project • Zaius - Barreleye G2 Specification 
http://opencompute.org 33 
11.8  Power – Voltage Regulation Requirement Guideline The following table summarizes the high-level power requirements for design of Zaius motherboard. Table: High-Level Power Requirements  Rail Name Rail Net Quantity Voltage Current (each) Notes 48V P48V 1 54V 26Atdc/35Amax Input to tray   
12V P12V 1 12.00V 50A PCIe slots, fans, SSD’s, HD 5V P5V 1 5.00V 1.50A HD CPU Core Vdd (core) 2 0.86V (0.6V-1.1V) 297Atdc/329.3Apk 300W TDP CPU 
CPU Cache Vcs (cache) 2 1.00V 11.6A  CPU Nest Vdn (nest) 2 0.86V 74.4A  CPU I/O Vio (I/O bus) 2 1.00V 21.0A  CPU PLL Avdd/Dvdd 2 1.50V 2.0A  CPU STBY Vsb 2 1.10V 1.0A  CPU STBY  P3V3 (V3P3sb) 2 3.30V Xxx mA Pending. To be added later DDR4 Memory VDDQ (CPU Vddr included) 4 1.20V 94.2Atdc /104Apk 16GB DIMM, 8 slots per rail 
DDR4  Memory VTT Term 8 0.60V 1.14Atdc / 2Apk Derived from VDDQ DDR4 Memory VPP 4 2.5V 9.5Atdc /12Apk DIMMs AST25X0 EC, E9235 SATA Controller, Renesas USB controller 
P3V3_stby 1 3.30V 0.9A (0.2A+0.3A+0.4A)  
 



Open Compute Project • Zaius - Barreleye G2 Specification 
http://opencompute.org 34 
11.9  Barreleye G2 Hard Drive Cage Power Hard drive backplane and expander board is powered from Fan power board independent of motherboard. More details on hard driver power will be added to this section in further revisions. 
   


Open Compute Project • Zaius - Barreleye G2 Specification 
http://opencompute.org 35 
12  I/O System 12.1  PCIe Slot Connector Zaius motherboard has 64 of the 84 lanes allocated as standard PCIe slot connectors and 16 lanes allocated for a OCP Mezz 2.0 connector as follows: ●  3 x16 PCIe slots ●  2 x8 PCIe slots ●  1 x16 OCP Mezz 2.0 connector (12mm baseboard stacking height) Figure: 5 PCIe slots (PE0-PE4) / 1 Mezz Slot Placement on Motherboard and Mapping to Chassis Front (Zaius Sled and Barreleye G2 2OU 5xPCI Cage Front)  
  
   


Open Compute Project • Zaius - Barreleye G2 Specification 
http://opencompute.org 36 
Table: 5 PCIe Slot (PE0-PE4) / 1 Mezz Slot Routing to Respective CPU Ports (Table Also has Details on Card Form Factors in Each Slot) PCIe  Slot  Bus  Width Source CPU Port Speed Bifurcation CAPI Support Supported Card Size Card Length x Bottom Height x Top Height PE0 x8 CPU0 PEC1 Gen4 - - Expanded-Slot 6.600”x0.570” x0.570” PE1 x16 CPU0 PEC0 Gen4 - Y Single-Slot 6.600”x0.105” x0.570” PE2 x16 CPU0 PEC2 Gen4 2 x8 Y 1.5-Slot 6.600”x0.105” x0.970” PE3 x16 CPU1 PEC0 Gen4 - Y Double-Slot 6.600"x0.105"  x1.370" PE4 x8 CPU1 PEC1 Gen4 2 x8 or  1 x8+2 x4 - Expanded-Slot 6.600”x0.570” x0.570” MEZZ0 x16 CPU1 PEC2 Gen4 2 x8 or 1x8 + 2x4 Y OCP Mezz 2.0  
 12.2  NV-Link/OpenCAPI Each processor supports 2 bricks (16 total lanes) of 25Gbp/s NVLink/OpenCAPI connections. Zaius motherboard routes the NV-Link/OpenCAPI lanes to two 37-pin connectors directly in front of each processor.  For each processor, the "bottom" connector contains x8 lanes numbered 0-10, the "top" connector contains x8 lanes numbered 13-23.  Control and clock sideband signals are routed to a separate SATA 7-pin form factor connector in front of each processor. 12.3  Network Zaius motherboard front panel optionally provides 2 RJ45 gigabit Ethernet connections in a dual stack connector.  Top Ethernet port connects to BCM5719A PCIe Ethernet.  Bottom port connects to BMC-only BCM54612 PHY. 12.3.1  BMC-only Gigabit Ethernet (optional) A Broadcom BCM54612 RGMII capable PHY and front panel RJ45 connector with LINK and ACT LEDs will be used to connect BMC port RGMII2.  This Ethernet port is only usable by the BMC for management purposes and is not connected to the host CPUs.   



Open Compute Project • Zaius - Barreleye G2 Specification 
http://opencompute.org 37 
12.3.2  BCM5719A PCIe Gigabit Ethernet LOM (optional) A Broadcom BCM5719A PCIe network controller is used in an optionally stuffed LAN-on-motherboard (LOM) role.  Port 0 of the controller connects to a front panel RJ45 connector with LINK and ACT LEDs, the other ports are unused.  The 4X PCIe lanes for the LOM are connected to lanes 8,9,10,11 of the LOM+VGA connector (optional). NCSI signals of the BCM5719A are be connected to the BMC as specified in the block diagram. 12.3.3  NC-SI Zaius provides 3 sources for high-speed NC-SI/RMII remote management.  All NC-SI sources are connected to BMC RMII1 port using an on-board mux that is controllable by the BMC.  Multi-drop connections and/or hardware arbitration is not supported.  BMC firmware is responsible for enumerating all NC-SI sources during initialization to detect network devices and assigning priority order as follows: ●  HDMI connector with custom pinout ●  BCM5719A LOM (optional) ●  OCP Mezzanine 2.0 slot 12.4  USB Zaius has two USB ports on a stacked (with RJ45 serial) connector on the front panel. The top USB port is connected to the Renesas USB controller and routed to support USB 3.0 operation (5Gbps).  The bottom USB port is connected to the USB 2.0 host port of the BMC.   Zaius will also support USB on each PCIe slot connected to the 7-port USB hub downstream of the host controller.  USB1.1 will be supported on these interfaces. Overcurrent protection is provided for the USB ports.  12.5  SATA Marvell 88SE9235 4 port SATA controller is used for SATA support. This controller is wired to a PCIe x2 of CPU0 as showed in block diagram.  
 SATA0 port will connect to a 22-pin header supporting both data and power (Amphenol G16CE41210W3EU or equivalent).  Standard signal and power pinouts for SATA are used on this connector.  See table below.  SATA1 port will connect to a M.2 2280 form factor connector (M-keyed). Marvell 88SE9235 I2C shall be connected to the BMC via appropriate I2C switches.  Table:  SATA Connector Pinout Pin Number Net Function 


Open Compute Project • Zaius - Barreleye G2 Specification 
http://opencompute.org 38 
S1 GND Tied directly to ground S2 TX+ Differential Transmit Signal Positive S3 TX- Differential Transmit Signal Negative S4 GND Tied directly to ground S5 RX- Differential Receive Signal Negative S6 RX+ Differential Receive Signal Positive S7 GND Tied directly to ground     Mechanical Key P1 NC No need to supply 3.3V power P2 NC No need to supply 3.3V power P3 NC No need to supply 3.3V power P4 GND Tied directly to ground P5 GND Tied directly to ground P6 GND Tied directly to ground - SATA present P7 VDD_5V Main logic power rail for hard drives P8 VDD_5V Main logic power rail for hard drives P9 VDD_5V Main logic power rail for hard drives P10 GND Tied directly to ground P11 GND Tied directly to ground P12 GND Tied directly to ground P13 VDD_12V_PER Spindle power rail for hard drives P14 VDD_12V_PER Spindle power rail for hard drives 



Open Compute Project • Zaius - Barreleye G2 Specification 
http://opencompute.org 39 
P15 VDD_12V_PER Spindle power rail for hard drives  Signals are to be routed to support operation up to 6Gb/s. 12.6  Buttons and LEDs:   Figure: LEDs and Buttons in the Front Panel of Barreleye G2 Tray 
 12.6.1  Buttons A reset button (black) and a power button (blue) are mounted at the front edge of the Motherboard. Power Button is on the left of the Reset button. All devices are capable of being manually reset to a known state via the Reset button. The power button is pressed for ~4 seconds to power off the server. When the system is powered off a press and release of the power button would power the server on.  More details on exact timing of power and reset button press and subsequent behavior will be added in the next revisions of this document as it is refined.  12.6.2  LEDs These LEDs are located on the front edge of the PCB and exposed to the front panel.  They will be clearly labeled on the silkscreen. On front panel of the tray LEDs are listed in the preferred left-to-right order as seen in the below front panel picture: ●  Blue LED: Indicates standby power good. ●  Green LED: Indicates All Power Good (from Sequencer). ●  Green LED: System Boot Status (driven from BMC GPIO) ●  Yellow LED: Indicates HDD activity.  This is the GPIO0 signal from the Marvell 88SE9235 for SATA drive activity.  ●  Yellow LED: Attention (machine locator, driven from BMC GPIO) - this LED should be placed away from the HDD activity LED, either on the left or right side of the mother board. ●  Red LED: Platform fault.  Driven from BMC GPIO. ●  Red LED: Onboard drive fault.  Driven from BMC GPIO      


Open Compute Project • Zaius - Barreleye G2 Specification 
http://opencompute.org 40 
12.7  Fan Connector & LEDs 12.7.1  Barreleye G2 Fans 12.7.1.1  Barreleye G2 Fan Connectors In Barreleye G2, fan connectors are present on Fan / Power board. Figure: Fan / Power Board and Cable in Barreleye G2 Chassis 12.7.1.2  Long FAN cable 
 
 12.7.1.3  Short FAN cable 
 


Open Compute Project • Zaius - Barreleye G2 Specification 
http://opencompute.org 41 
 


Open Compute Project • Zaius - Barreleye G2 Specification 
http://opencompute.org 42 
Barreleye G2 Fan LEDs Each of 6 fan modules in Barreleye G2 Chassis have 2 LEDs each with following behavior.  Fan LED Behavior LED Color Function LED Pattern Comment Blue Fan normal operation Always light Bi-color LED and integrated Fan modules. It will light Red for several seconds when the system is just powered on, it will change to blue when the fan duty exceed 30%. Red Fan fault, duty cycle < 30% Always light 
 Figure: 3D Rendering of Barreleye G2 Fans and Rear View Indicating 2 LEDs on Each of the 6 Fans. 
 
 12.7.2  Zaius Fan Connectors Zaius motherboard has 4 4-pin fan connectors capable of supporting 12V fans.  The pinout of the fan connectors is as below.  System fan control and monitoring is provided by the BMC.  Note this pinout does NOT follow the standard “4-wire PWM fan” specification.  Pin Function 


Open Compute Project • Zaius - Barreleye G2 Specification 
http://opencompute.org 43 
1 Control (PWM) 2 Sense (Tach) 3 +12V 4 GND  12.8  UART Connector 12.8.1  System UART The primary system (host) serial port is connected to UART1 of the BMC and routed to a stacked RJ45+USB connector (Foxconn UB11123-YC0F-4F or similar) on the front panel.  Pinout for the RJ45 port is to follow the "Cisco" pinout variant.  Only TX/RX/GND signals should be connected, the modem control signals are no-connect.  Signal levels are to follow RS-232 standard (+12V/-12V). Table: RJ45 serial pinout Signal Pin UART0_RX 3 GND 4 GND 5 UART0_TX 6 
12.8.2  BMC Debug UART BMC debug console UART5 should be connected to a 3pin 2.54mm header near the front of the board with the following pinout.  Signal levels are to follow the RS-232 standard (+12V/-12V):                    Table: BMC debug serial header pinout Signal Pin UART5_TX 1 GND 2 UART5_RX 3 	
   	
   	
  



Open Compute Project • Zaius - Barreleye G2 Specification 
http://opencompute.org 44 
13  Mechanical 13.1  Barreleye G2 – 2OU Mechanical 13.1.1  Barreleye G2 Chassis The 2 OU chassis has the dimensions, 537 x 801 x 92.3mm.       



Open Compute Project • Zaius - Barreleye G2 Specification 
http://opencompute.org 45 
13.1.2  Barreleye G2 Top View Barreleye G2 supports 24 Hot-Pluggable 2.5” SAS hard drives/ 20 NVMe drives and Fan modules. There are 4 main boards in the system.  They are Motherboard, Tri-mode Expander board, Fan / Power Distribution Board and Tri-mode HDD Back Plane.  Figure: Top View [ Barreleye G2 GPU SKU] Diagram  
   


Open Compute Project • Zaius - Barreleye G2 Specification 
http://opencompute.org 46 
Figure: Top View - System Infrastructure [ 5* PCI-e Card SKU] Diagram 
  Figure: 3D Barreleye G2 Rendering [ 5* PCI-e Card SKU] Diagram - In a tray 
 13.1.3  Barreleye G2 Front View Barreleye supports two 2 x8 PCIe Gen4 3 X16 PCIe and 1 MEZ Card. The I/O connectors are 


Open Compute Project • Zaius - Barreleye G2 Specification 
http://opencompute.org 47 
located on the front. There is one HDD Tray on the right which contains 24pcs Hot-Pluggable 2.5” HDD drives.   Figure: Front View 
 13.1.4  Barreleye G2 Rear View There is one Bus bar clip and 6 Hot-pluggable Fan Modules on the rear wall.  Figure: Rear View 
   


Open Compute Project • Zaius - Barreleye G2 Specification 
http://opencompute.org 48 
13.1.5  Barreleye G2 / Zaius Mother Board The dimensions of Barreleye G2’s Main board / Zaius Motherboard are 564x330mm.  It supports two Power 9 LaGrange CPUs and 32 DIMMs.  
  


Open Compute Project • Zaius - Barreleye G2 Specification 
http://opencompute.org 49 
Figure: Front Isometric View of Motherboard 
 13.1.6  Barreleye G2 FPDB (Fan/Power Distribution Board) FPDB provides power for 6 fans, Tri-mode Expander board, Tri-mode HDD Back Plane, and GPU using with two 48V- to -12V bricks.  
   


Open Compute Project • Zaius - Barreleye G2 Specification 
http://opencompute.org 50 
13.1.7  Barreleye G2 Tri-mode Expander Board This board conducts the SAS/PCIe signals from Tri-mode adapter to Tri-mode HDD BP through the Slim SAS cables. 
   


Open Compute Project • Zaius - Barreleye G2 Specification 
http://opencompute.org 51 
13.1.8  Barreleye G2 OCP MEZZ The OCP-MEZZ Card with 2 configurations and how they get exposed to the front of chassis  
   


Open Compute Project • Zaius - Barreleye G2 Specification 
http://opencompute.org 52 
13.1.9  Barreleye G2 Tri-mode Back Plane x 24  
 
   


Open Compute Project • Zaius - Barreleye G2 Specification 
http://opencompute.org 53 
13.1.10  Barreleye G2 Hard Drive Tray & Installation The dimension of Hard Drive Tray is 501mm (L) x 151.9mm (W) x 88.9mm (H). 
 
 


Open Compute Project • Zaius - Barreleye G2 Specification 
http://opencompute.org 54 
13.2  Zaius Sled – 2.6” tall The Zaius sled fits the motherboard and 4 rear 60mm fans.  The dimensions of the sled are approximately 340x610x66mm (13.4”x24”x2.6”).  It is intended for use in the 1.5OU Open Rack Deployment Shelf. Figure: Front Isometric View of Zaius Sled 
  13.2.1  Zaius Sled in 1.5OU Deployment Shelf The Zaius 1.5OU deployment shelf is 537x660x72mm (21”x26”x2.8”), and fits 1 Zaius sled with a 6.4” wide accessory space to the right of the sled.  The shelf latches the sled into position and connects to the rack vertical bus bar.  The shelf connects to the rear vertical bus bar provided by the rack and provides a horizontal 48V bus bar in the rear to power the Zaius sled and any additional attached devices in the same shelf. 


Open Compute Project • Zaius - Barreleye G2 Specification 
http://opencompute.org 55 
Figure: Zaius Sled in 1.5OU Deployment Shelf. 
	
  13.3  Rack and Sled Interaction   Rack for Barreleye G2 / Zaius Chassis is standard 48V OCP Rack V2. The rack will follow the Open Rack Specification shown here: http://files.opencompute.org/oc/public.php?service=files&t=8d2264171f72aa8a86d0e08a3504c740 Rack and power shelf are still under development. Details will be shared in upcoming revisions of this document.   


Open Compute Project • Zaius - Barreleye G2 Specification 
http://opencompute.org 56 
14  Power Distribution from Bus Bar  Power connections from bus bar to mother board might vary based on different chassis implementations of Zaius motherboard.  14.1  Barreleye G2 Chassis Barreleye G2 Chassis receives its power via a single 48V bus bar clip located at the rear of the server.  Figure: Barreleye G2 Chassis Rear View  
 14.1.1  Barreleye G2 FPDB (Fan/Power Distribution Board) Fan /Power distribution board terminal connectors are connected to bus bar clip and provide power for fans, Tri-mode Expander board, HDD Back Plane and GPU from two 48V-to-12V bricks. 
   
 



Open Compute Project • Zaius - Barreleye G2 Specification 
http://opencompute.org 57 
Figure: Barreleye G2 Sled - Cable Connecting Bus Bar Connector to Power / Fan Board 
  
   


Open Compute Project • Zaius - Barreleye G2 Specification 
http://opencompute.org 58 
14.2  Zaius Sled Bus Bar Connection Zaius sled uses a horizontal bus bar connector that connects to the Zaius 1.5OU deployment shelf and allows the tray to be placed anywhere along the length of the horizontal bus bar contained within each deployment shelf. Figure: Zaius Sled Horizontal Bus Bar Connector 
 


Open Compute Project • Zaius - Barreleye G2 Specification 
http://opencompute.org 59 
14.2.1  Zaius Sled/Shelf Connection Detail Views Figure: Sled/Shelf Bus Bar Top View 
 Figure: Tray/Shelf Bus Bar Isometric Cutaway View 
 14.3  Motherboard Power Connector Motherboard uses an on-board input power connector to receive 48V on the rear of the tray. For 


Open Compute Project • Zaius - Barreleye G2 Specification 
http://opencompute.org 60 
Barreleye G2 this input would come from Fan Board, for Zaius the cable directly attaches to the rear bus bar connector. This connector is a latching 4 pin vertical Molex MiniFit Sr connector supporting 40A@48VDC. 14.4  Power Distribution on Motherboard: Further details on how bus bar clip is wired to the Zaius motherboard, max power rating supported by the server and internal distribution of power on the motherboard are in the “Motherboard Power System” Section. 
15  48V Lunch Box 15.1  48V Lunch Box Overview The 48V Lunch Box provides DC input power for server when it is operated in a standalone fashion. Standalone use cases include: ●  on a bench for bring up/debug ●  on a bench or engineer’s desk for evaluation or code development ●  Chamber testing of a single unit The 48V Lunch Box is intended to be a convenient way to power server without having to place it in a rack. 
 15.2  Objectives The 48V Lunch Box must: ●  Be safe to use in a lab environment with no expose high voltage or high current contacts ●  Be flexible in its placement on a bench for those who are evaluating or doing debug ●  Not impede airflow if this is important for testing and other needs ●  Have a minimum EMI footprint to allow testing of a single unit in the lab ●  Use off-the-shelf components where possible (such as the rectifier) ●  Support AC cabling to different AC outlets/voltage 


Open Compute Project • Zaius - Barreleye G2 Specification 
http://opencompute.org 61 
15.3  Zaius 48V Lunch Box Interfaces 15.3.1  AC Connector The Zaius 48V Lunch Box supports an IEC320 C15 connector to connect to a wide range of AC outlets, at the maximum power of Zaius (around 1700W). 15.3.2  AC Input Cable Different AC cables are supported to allow for different use cases, further details will be provided in future revisions of the spec. 15.3.3  Zaius 48V Lunch Box Power Supply Modules (e.g. Rectifiers) The rectifier supports a minimum of 1700W at low line (~110VAC) to enable the maximum flexibility. Figure: 3D Rendering of 48V Lunchbox Connected to AC Outlet 
 Figure: 3D Rendering of 48V Lunch Box Connected to Server Power Cable 
 


Open Compute Project • Zaius - Barreleye G2 Specification 
http://opencompute.org 62 
Figure: How Lunchbox Connects to Server Chassis / Sled via Cable (Barreleye G2 2OU Example) 
   


Open Compute Project • Zaius - Barreleye G2 Specification 
http://opencompute.org 63 
16  Regulatory & Safety Requirements The entire board is RoHS-6 compliant.  Basic Compliance Requirements: 16.1  Safety The equipment must meet all applicable safety requirements and certifications when operating under maximum normal load conditions.  Applicable standards may include the following:  ●  UL/CSA/IEC/EN 60950-1 ●  UL/CSA/IEC/EN 62368-1 16.2  EMC The equipment must meet the following requirements when operating under typical load conditions and with all ports fully loaded. 16.2.1  Emissions 6dB margin from the Class A limit is required for all emission test, both radiated emission and conducted emission. When the EUT is DC powered, DC line conducted emission test is required.  Primary EMC Standards apply to emission test include, but not limited to  ●  FCC Part 15, Subpart B  ●  EN 55022: 2010 / CISPR 22: 2008 (Modified) ●  EN 55032: 2012 / CISPR 32: 2012 (Modified) - Effective 05/03/2017 ●  EN61000-3-2: 2006/A1: 2009/A2: 2009 ●  EN61000-3-3: 2008 For DC power related testing, when applicable GR 1089 / GR 3160 may be referenced. 16.2.2  Immunity  Primary EMC Standards apply to immunity test include, but not limited to  ●  EN 55024: 2010 / CISPR 24: 2010 (Modified) ●  CISPR 35: 2014 (current publication: CISPR/I/463/FDIS 2013-12) Each individual basic standard for immunity test has its specific passing requirement as illustrated below. When the EUT is DC powered, immunity test involves disturbance applied to power line apply to the DC input power.  ●  EN61000-4-2 Electrostatic Discharge Immunity (6kV contact, 8kV air) ●  EN61000-4-3 Radiated Immunity [> 10V/m] ●  EN61000-4-4 Electrical Fast Transient Immunity (1kV power (AC), 0.5kV signal) ●  EN61000-4-5 Surge AC Port (2kV CM, 1kV DM) ●  EN61000-4-5 Surge Signal Port (2KV CM, 1KVDM) ●  EN61000-4-5 Surge DC Port (0.5kVCM, 0.5KVDM) ●  EN61000-4-6 Immunity to Conducted Disturbances [> 10V rms] ●  EN61000-4-8 Power Frequency Magnetic Field Immunity (30A/m), when applicable ●  EN61000-4-11 Voltage Dips, Short Interruptions, and Voltage Variations 



Open Compute Project • Zaius - Barreleye G2 Specification 
http://opencompute.org 64 
For DC power related testing, when applicable GR 1089 / GR 3160 may be referenced.  16.2.3  Country Specific EMC Requirement: Most countries / region have country specific / regional EMC requirements. In addition to above listed EMC standards, the equipment shall demonstrate compliance to standards which includes, but not limited to ●  CNS 13438: 2006 ●  AS/NZS CISPR22: 2009/A1:2010 ●  Industry Canada ICES-003 ●  VCCI V-3/2013-04 ●  KN 32 (Replacement of KN 22 effective January 1, 2016) ●  KN 35 (Replacement of KN 24 effective January 1, 2016) ●  ANATEL Resolution 242 / 323 / 442 